(kicad_pcb
	(version 20260206)
	(generator "pcbnew")
	(generator_version "10.0")
	(general
		(thickness 1.6)
		(legacy_teardrops no)
	)
	(paper "A4")
	(title_block
		(title "04192023_DAF0TMB3IC0_F0TG_MB_C_brd_V02_OCP.brd")
		(comment 1 "Grand Teton / footprints 6757-6763 of 8354")
	)
	(layers
		(0 "F.Cu" signal "TOP")
		(4 "In1.Cu" signal "GND")
		(6 "In2.Cu" signal "IN1")
		(8 "In3.Cu" signal "GND1")
		(10 "In4.Cu" signal "IN2")
		(12 "In5.Cu" signal "GND2")
		(14 "In6.Cu" signal "IN3")
		(16 "In7.Cu" signal "GND3")
		(18 "In8.Cu" signal "VCC")
		(20 "In9.Cu" signal "VCC1")
		(22 "In10.Cu" signal "GND4")
		(24 "In11.Cu" signal "IN4")
		(26 "In12.Cu" signal "GND5")
		(28 "In13.Cu" signal "IN5")
		(30 "In14.Cu" signal "GND6")
		(32 "In15.Cu" signal "IN6")
		(34 "In16.Cu" signal "GND7")
		(2 "B.Cu" signal "BOTTOM")
		(9 "F.Adhes" user "F.Adhesive")
		(11 "B.Adhes" user "B.Adhesive")
		(13 "F.Paste" user "Package Geometry/Pastemask Top")
		(15 "B.Paste" user "Package Geometry/Pastemask Bottom")
		(5 "F.SilkS" user "Ref Des/Silkscreen Top")
		(7 "B.SilkS" user "Ref Des/Silkscreen Bottom")
		(1 "F.Mask" user "Board Geometry/Soldermask Top")
		(3 "B.Mask" user "Board Geometry/Soldermask Bottom")
		(17 "Dwgs.User" user "User.Drawings")
		(19 "Cmts.User" user "User.Comments")
		(21 "Eco1.User" user "User.Eco1")
		(23 "Eco2.User" user "User.Eco2")
		(25 "Edge.Cuts" user "Board Geometry/Outline")
		(27 "Margin" user)
		(31 "F.CrtYd" user "Package Geometry/Place Bound Top")
		(29 "B.CrtYd" user "Package Geometry/Place Bound Bottom")
		(35 "F.Fab" user "Ref Des/Assembly Top")
		(33 "B.Fab" user "Ref Des/Assembly Bottom")
	)
	(footprint ""
		(layer "B.Cu")
		(at 143.3068 -13.762228 90)
		(property "Reference" "R1815"
			(at 0 0 90)
			(layer "B.SilkS")
			(hide yes)
			(effects
				(font
					(size 1.27 1.27)
				)
				(justify mirror)
			)
		)
		(property "Value" ""
			(at 0 0 90)
			(layer "B.Fab")
			(effects
				(font
					(size 1.27 1.27)
				)
				(justify mirror)
			)
		)
		(duplicate_pad_numbers_are_jumpers no)
		(fp_line
			(start 0.7874 -0.4064)
			(end -0.7874 -0.4064)
			(stroke
				(width 0.1524)
				(type default)
			)
			(layer "B.SilkS")
		)
		(fp_line
			(start -0.7874 -0.4064)
			(end -0.7874 0.4064)
			(stroke
				(width 0.1524)
				(type default)
			)
			(layer "B.SilkS")
		)
		(fp_line
			(start 0.7874 0.4064)
			(end 0.7874 -0.4064)
			(stroke
				(width 0.1524)
				(type default)
			)
			(layer "B.SilkS")
		)
		(fp_line
			(start -0.7874 0.4064)
			(end 0.7874 0.4064)
			(stroke
				(width 0.1524)
				(type default)
			)
			(layer "B.SilkS")
		)
		(fp_line
			(start 0.67945 -0.305054)
			(end 0.12065 -0.305054)
			(stroke
				(width 0.1)
				(type default)
			)
			(layer "B.Fab")
		)
		(fp_line
			(start 0.12065 -0.305054)
			(end 0.12065 -0.2794)
			(stroke
				(width 0.1)
				(type default)
			)
			(layer "B.Fab")
		)
		(fp_line
			(start -0.12065 -0.3048)
			(end -0.67945 -0.3048)
			(stroke
				(width 0.1)
				(type default)
			)
			(layer "B.Fab")
		)
		(fp_line
			(start -0.67945 -0.3048)
			(end -0.67945 0.3048)
			(stroke
				(width 0.1)
				(type default)
			)
			(layer "B.Fab")
		)
		(fp_line
			(start 0.12065 -0.2794)
			(end -0.12065 -0.2794)
			(stroke
				(width 0.1)
				(type default)
			)
			(layer "B.Fab")
		)
		(fp_line
			(start -0.12065 -0.2794)
			(end -0.12065 -0.3048)
			(stroke
				(width 0.1)
				(type default)
			)
			(layer "B.Fab")
		)
		(fp_line
			(start 0.12065 0.2794)
			(end 0.12065 0.3048)
			(stroke
				(width 0.1)
				(type default)
			)
			(layer "B.Fab")
		)
		(fp_line
			(start -0.120396 0.2794)
			(end 0.12065 0.2794)
			(stroke
				(width 0.1)
				(type default)
			)
			(layer "B.Fab")
		)
		(fp_line
			(start 0.67945 0.3048)
			(end 0.67945 -0.305054)
			(stroke
				(width 0.1)
				(type default)
			)
			(layer "B.Fab")
		)
		(fp_line
			(start 0.12065 0.3048)
			(end 0.67945 0.3048)
			(stroke
				(width 0.1)
				(type default)
			)
			(layer "B.Fab")
		)
		(fp_line
			(start -0.120396 0.3048)
			(end -0.120396 0.2794)
			(stroke
				(width 0.1)
				(type default)
			)
			(layer "B.Fab")
		)
		(fp_line
			(start -0.67945 0.3048)
			(end -0.120396 0.3048)
			(stroke
				(width 0.1)
				(type default)
			)
			(layer "B.Fab")
		)
		(pad "1" smd circle
			(at 0.40005 0 270)
			(size 0 0)
			(layers "B.Cu" "B.Mask" "B.Paste")
			(net "SCM_SYS_PWRBTN_N")
		)
		(pad "2" smd circle
			(at -0.40005 0 270)
			(size 0 0)
			(layers "B.Cu" "B.Mask" "B.Paste")
			(net "SCM_SYS_PWRBTN_R_N")
		)
	)
	(footprint ""
		(layer "B.Cu")
		(at 373.329454 -250.89231)
		(property "Reference" "C2592"
			(at 0 0 0)
			(layer "B.SilkS")
			(hide yes)
			(effects
				(font
					(size 1.27 1.27)
				)
				(justify mirror)
			)
		)
		(property "Value" ""
			(at 0 0 0)
			(layer "B.Fab")
			(effects
				(font
					(size 1.27 1.27)
				)
				(justify mirror)
			)
		)
		(duplicate_pad_numbers_are_jumpers no)
		(fp_line
			(start -0.7874 -0.4064)
			(end -0.7874 0.4064)
			(stroke
				(width 0.1524)
				(type default)
			)
			(layer "B.SilkS")
		)
		(fp_line
			(start -0.7874 0.4064)
			(end 0.7874 0.4064)
			(stroke
				(width 0.1524)
				(type default)
			)
			(layer "B.SilkS")
		)
		(fp_line
			(start 0.7874 -0.4064)
			(end -0.7874 -0.4064)
			(stroke
				(width 0.1524)
				(type default)
			)
			(layer "B.SilkS")
		)
		(fp_line
			(start 0.7874 0.4064)
			(end 0.7874 -0.4064)
			(stroke
				(width 0.1524)
				(type default)
			)
			(layer "B.SilkS")
		)
		(fp_line
			(start -0.67945 -0.3048)
			(end -0.67945 0.3048)
			(stroke
				(width 0.1)
				(type default)
			)
			(layer "B.Fab")
		)
		(fp_line
			(start -0.67945 0.3048)
			(end -0.120396 0.3048)
			(stroke
				(width 0.1)
				(type default)
			)
			(layer "B.Fab")
		)
		(fp_line
			(start -0.12065 -0.3048)
			(end -0.67945 -0.3048)
			(stroke
				(width 0.1)
				(type default)
			)
			(layer "B.Fab")
		)
		(fp_line
			(start -0.12065 -0.2794)
			(end -0.12065 -0.3048)
			(stroke
				(width 0.1)
				(type default)
			)
			(layer "B.Fab")
		)
		(fp_line
			(start -0.120396 0.2794)
			(end 0.12065 0.2794)
			(stroke
				(width 0.1)
				(type default)
			)
			(layer "B.Fab")
		)
		(fp_line
			(start -0.120396 0.3048)
			(end -0.120396 0.2794)
			(stroke
				(width 0.1)
				(type default)
			)
			(layer "B.Fab")
		)
		(fp_line
			(start 0.12065 -0.305054)
			(end 0.12065 -0.2794)
			(stroke
				(width 0.1)
				(type default)
			)
			(layer "B.Fab")
		)
		(fp_line
			(start 0.12065 -0.2794)
			(end -0.12065 -0.2794)
			(stroke
				(width 0.1)
				(type default)
			)
			(layer "B.Fab")
		)
		(fp_line
			(start 0.12065 0.2794)
			(end 0.12065 0.3048)
			(stroke
				(width 0.1)
				(type default)
			)
			(layer "B.Fab")
		)
		(fp_line
			(start 0.12065 0.3048)
			(end 0.67945 0.3048)
			(stroke
				(width 0.1)
				(type default)
			)
			(layer "B.Fab")
		)
		(fp_line
			(start 0.67945 -0.305054)
			(end 0.12065 -0.305054)
			(stroke
				(width 0.1)
				(type default)
			)
			(layer "B.Fab")
		)
		(fp_line
			(start 0.67945 0.3048)
			(end 0.67945 -0.305054)
			(stroke
				(width 0.1)
				(type default)
			)
			(layer "B.Fab")
		)
		(pad "1" smd circle
			(at 0.40005 0 180)
			(size 0 0)
			(layers "B.Cu" "B.Mask" "B.Paste")
			(net "PVDDCR_SOC_P0")
		)
		(pad "2" smd circle
			(at -0.40005 0 180)
			(size 0 0)
			(layers "B.Cu" "B.Mask" "B.Paste")
			(net "GND")
		)
	)
	(footprint ""
		(layer "B.Cu")
		(at 52.178458 -386.766562 90)
		(property "Reference" "C201"
			(at 0 0 90)
			(layer "B.SilkS")
			(hide yes)
			(effects
				(font
					(size 1.27 1.27)
				)
				(justify mirror)
			)
		)
		(property "Value" ""
			(at 0 0 90)
			(layer "B.Fab")
			(effects
				(font
					(size 1.27 1.27)
				)
				(justify mirror)
			)
		)
		(duplicate_pad_numbers_are_jumpers no)
		(fp_line
			(start 0.299974 -0.150114)
			(end -0.299974 -0.150114)
			(stroke
				(width 0.1)
				(type default)
			)
			(layer "B.Fab")
		)
		(fp_line
			(start -0.299974 -0.150114)
			(end -0.299974 0.150114)
			(stroke
				(width 0.1)
				(type default)
			)
			(layer "B.Fab")
		)
		(fp_line
			(start 0.299974 0.150114)
			(end 0.299974 -0.150114)
			(stroke
				(width 0.1)
				(type default)
			)
			(layer "B.Fab")
		)
		(fp_line
			(start -0.299974 0.150114)
			(end 0.299974 0.150114)
			(stroke
				(width 0.1)
				(type default)
			)
			(layer "B.Fab")
		)
		(pad "1" smd rect
			(at 0.2667 0 270)
			(size 0.3048 0.381)
			(layers "B.Cu" "B.Mask" "B.Paste")
			(net "P0V9_CPU1_RT0_2A_2D")
		)
		(pad "2" smd rect
			(at -0.2667 0 270)
			(size 0.3048 0.381)
			(layers "B.Cu" "B.Mask" "B.Paste")
			(net "GND")
		)
	)
	(footprint ""
		(layer "B.Cu")
		(at 130.657092 -50.302922 90)
		(property "Reference" "R6067"
			(at 0 0 90)
			(layer "B.SilkS")
			(hide yes)
			(effects
				(font
					(size 1.27 1.27)
				)
				(justify mirror)
			)
		)
		(property "Value" ""
			(at 0 0 90)
			(layer "B.Fab")
			(effects
				(font
					(size 1.27 1.27)
				)
				(justify mirror)
			)
		)
		(duplicate_pad_numbers_are_jumpers no)
		(fp_line
			(start 0.7874 -0.4064)
			(end -0.7874 -0.4064)
			(stroke
				(width 0.1524)
				(type default)
			)
			(layer "B.SilkS")
		)
		(fp_line
			(start -0.7874 -0.4064)
			(end -0.7874 0.4064)
			(stroke
				(width 0.1524)
				(type default)
			)
			(layer "B.SilkS")
		)
		(fp_line
			(start 0.7874 0.4064)
			(end 0.7874 -0.4064)
			(stroke
				(width 0.1524)
				(type default)
			)
			(layer "B.SilkS")
		)
		(fp_line
			(start -0.7874 0.4064)
			(end 0.7874 0.4064)
			(stroke
				(width 0.1524)
				(type default)
			)
			(layer "B.SilkS")
		)
		(fp_line
			(start 0.67945 -0.305054)
			(end 0.12065 -0.305054)
			(stroke
				(width 0.1)
				(type default)
			)
			(layer "B.Fab")
		)
		(fp_line
			(start 0.12065 -0.305054)
			(end 0.12065 -0.2794)
			(stroke
				(width 0.1)
				(type default)
			)
			(layer "B.Fab")
		)
		(fp_line
			(start -0.12065 -0.3048)
			(end -0.67945 -0.3048)
			(stroke
				(width 0.1)
				(type default)
			)
			(layer "B.Fab")
		)
		(fp_line
			(start -0.67945 -0.3048)
			(end -0.67945 0.3048)
			(stroke
				(width 0.1)
				(type default)
			)
			(layer "B.Fab")
		)
		(fp_line
			(start 0.12065 -0.2794)
			(end -0.12065 -0.2794)
			(stroke
				(width 0.1)
				(type default)
			)
			(layer "B.Fab")
		)
		(fp_line
			(start -0.12065 -0.2794)
			(end -0.12065 -0.3048)
			(stroke
				(width 0.1)
				(type default)
			)
			(layer "B.Fab")
		)
		(fp_line
			(start 0.12065 0.2794)
			(end 0.12065 0.3048)
			(stroke
				(width 0.1)
				(type default)
			)
			(layer "B.Fab")
		)
		(fp_line
			(start -0.120396 0.2794)
			(end 0.12065 0.2794)
			(stroke
				(width 0.1)
				(type default)
			)
			(layer "B.Fab")
		)
		(fp_line
			(start 0.67945 0.3048)
			(end 0.67945 -0.305054)
			(stroke
				(width 0.1)
				(type default)
			)
			(layer "B.Fab")
		)
		(fp_line
			(start 0.12065 0.3048)
			(end 0.67945 0.3048)
			(stroke
				(width 0.1)
				(type default)
			)
			(layer "B.Fab")
		)
		(fp_line
			(start -0.120396 0.3048)
			(end -0.120396 0.2794)
			(stroke
				(width 0.1)
				(type default)
			)
			(layer "B.Fab")
		)
		(fp_line
			(start -0.67945 0.3048)
			(end -0.120396 0.3048)
			(stroke
				(width 0.1)
				(type default)
			)
			(layer "B.Fab")
		)
		(pad "1" smd rect
			(at 0.40005 0 90)
			(size 0.4572 0.508)
			(layers "B.Cu" "B.Mask" "B.Paste")
			(net "JTAG_SCM_TDO_R")
		)
		(pad "2" smd rect
			(at -0.40005 0 90)
			(size 0.4572 0.508)
			(layers "B.Cu" "B.Mask" "B.Paste")
			(net "JTAG_SCM_TDI")
		)
	)
	(footprint ""
		(layer "B.Cu")
		(at 375.278396 -395.148562 90)
		(property "Reference" "C1020"
			(at 0 0 90)
			(layer "B.SilkS")
			(hide yes)
			(effects
				(font
					(size 1.27 1.27)
				)
				(justify mirror)
			)
		)
		(property "Value" ""
			(at 0 0 90)
			(layer "B.Fab")
			(effects
				(font
					(size 1.27 1.27)
				)
				(justify mirror)
			)
		)
		(duplicate_pad_numbers_are_jumpers no)
		(fp_line
			(start 0.299974 -0.150114)
			(end -0.299974 -0.150114)
			(stroke
				(width 0.1)
				(type default)
			)
			(layer "B.Fab")
		)
		(fp_line
			(start -0.299974 -0.150114)
			(end -0.299974 0.150114)
			(stroke
				(width 0.1)
				(type default)
			)
			(layer "B.Fab")
		)
		(fp_line
			(start 0.299974 0.150114)
			(end 0.299974 -0.150114)
			(stroke
				(width 0.1)
				(type default)
			)
			(layer "B.Fab")
		)
		(fp_line
			(start -0.299974 0.150114)
			(end 0.299974 0.150114)
			(stroke
				(width 0.1)
				(type default)
			)
			(layer "B.Fab")
		)
		(pad "1" smd rect
			(at 0.2667 0 270)
			(size 0.3048 0.381)
			(layers "B.Cu" "B.Mask" "B.Paste")
			(net "P0V9_CPU0_RT3_2A_2D")
		)
		(pad "2" smd rect
			(at -0.2667 0 270)
			(size 0.3048 0.381)
			(layers "B.Cu" "B.Mask" "B.Paste")
			(net "GND")
		)
	)
	(footprint ""
		(layer "B.Cu")
		(at 240.327942 -290.564062)
		(property "Reference" "PR6500"
			(at 0 0 0)
			(layer "B.SilkS")
			(hide yes)
			(effects
				(font
					(size 1.27 1.27)
				)
				(justify mirror)
			)
		)
		(property "Value" ""
			(at 0 0 0)
			(layer "B.Fab")
			(effects
				(font
					(size 1.27 1.27)
				)
				(justify mirror)
			)
		)
		(duplicate_pad_numbers_are_jumpers no)
		(fp_line
			(start -0.7874 -0.4064)
			(end -0.7874 0.4064)
			(stroke
				(width 0.1524)
				(type default)
			)
			(layer "B.SilkS")
		)
		(fp_line
			(start -0.7874 0.4064)
			(end 0.7874 0.4064)
			(stroke
				(width 0.1524)
				(type default)
			)
			(layer "B.SilkS")
		)
		(fp_line
			(start 0.7874 -0.4064)
			(end -0.7874 -0.4064)
			(stroke
				(width 0.1524)
				(type default)
			)
			(layer "B.SilkS")
		)
		(fp_line
			(start 0.7874 0.4064)
			(end 0.7874 -0.4064)
			(stroke
				(width 0.1524)
				(type default)
			)
			(layer "B.SilkS")
		)
		(fp_line
			(start -0.67945 -0.3048)
			(end -0.67945 0.3048)
			(stroke
				(width 0.1)
				(type default)
			)
			(layer "B.Fab")
		)
		(fp_line
			(start -0.67945 0.3048)
			(end -0.120396 0.3048)
			(stroke
				(width 0.1)
				(type default)
			)
			(layer "B.Fab")
		)
		(fp_line
			(start -0.12065 -0.3048)
			(end -0.67945 -0.3048)
			(stroke
				(width 0.1)
				(type default)
			)
			(layer "B.Fab")
		)
		(fp_line
			(start -0.12065 -0.2794)
			(end -0.12065 -0.3048)
			(stroke
				(width 0.1)
				(type default)
			)
			(layer "B.Fab")
		)
		(fp_line
			(start -0.120396 0.2794)
			(end 0.12065 0.2794)
			(stroke
				(width 0.1)
				(type default)
			)
			(layer "B.Fab")
		)
		(fp_line
			(start -0.120396 0.3048)
			(end -0.120396 0.2794)
			(stroke
				(width 0.1)
				(type default)
			)
			(layer "B.Fab")
		)
		(fp_line
			(start 0.12065 -0.305054)
			(end 0.12065 -0.2794)
			(stroke
				(width 0.1)
				(type default)
			)
			(layer "B.Fab")
		)
		(fp_line
			(start 0.12065 -0.2794)
			(end -0.12065 -0.2794)
			(stroke
				(width 0.1)
				(type default)
			)
			(layer "B.Fab")
		)
		(fp_line
			(start 0.12065 0.2794)
			(end 0.12065 0.3048)
			(stroke
				(width 0.1)
				(type default)
			)
			(layer "B.Fab")
		)
		(fp_line
			(start 0.12065 0.3048)
			(end 0.67945 0.3048)
			(stroke
				(width 0.1)
				(type default)
			)
			(layer "B.Fab")
		)
		(fp_line
			(start 0.67945 -0.305054)
			(end 0.12065 -0.305054)
			(stroke
				(width 0.1)
				(type default)
			)
			(layer "B.Fab")
		)
		(fp_line
			(start 0.67945 0.3048)
			(end 0.67945 -0.305054)
			(stroke
				(width 0.1)
				(type default)
			)
			(layer "B.Fab")
		)
		(pad "1" smd circle
			(at 0.40005 0 180)
			(size 0 0)
			(layers "B.Cu" "B.Mask" "B.Paste")
			(net "GND")
		)
		(pad "2" smd circle
			(at -0.40005 0 180)
			(size 0 0)
			(layers "B.Cu" "B.Mask" "B.Paste")
			(net "P1V8_RETIMER_CPU0_MODE")
		)
	)
	(footprint ""
		(layer "B.Cu")
		(at 423.015156 -244.08511)
		(property "Reference" "R382"
			(at 0 0 0)
			(layer "B.SilkS")
			(hide yes)
			(effects
				(font
					(size 1.27 1.27)
				)
				(justify mirror)
			)
		)
		(property "Value" ""
			(at 0 0 0)
			(layer "B.Fab")
			(effects
				(font
					(size 1.27 1.27)
				)
				(justify mirror)
			)
		)
		(duplicate_pad_numbers_are_jumpers no)
		(fp_line
			(start -0.7874 -0.4064)
			(end -0.7874 0.4064)
			(stroke
				(width 0.1524)
				(type default)
			)
			(layer "B.SilkS")
		)
		(fp_line
			(start -0.7874 0.4064)
			(end 0.7874 0.4064)
			(stroke
				(width 0.1524)
				(type default)
			)
			(layer "B.SilkS")
		)
		(fp_line
			(start 0.7874 -0.4064)
			(end -0.7874 -0.4064)
			(stroke
				(width 0.1524)
				(type default)
			)
			(layer "B.SilkS")
		)
		(fp_line
			(start 0.7874 0.4064)
			(end 0.7874 -0.4064)
			(stroke
				(width 0.1524)
				(type default)
			)
			(layer "B.SilkS")
		)
		(fp_line
			(start -0.67945 -0.3048)
			(end -0.67945 0.3048)
			(stroke
				(width 0.1)
				(type default)
			)
			(layer "B.Fab")
		)
		(fp_line
			(start -0.67945 0.3048)
			(end -0.120396 0.3048)
			(stroke
				(width 0.1)
				(type default)
			)
			(layer "B.Fab")
		)
		(fp_line
			(start -0.12065 -0.3048)
			(end -0.67945 -0.3048)
			(stroke
				(width 0.1)
				(type default)
			)
			(layer "B.Fab")
		)
		(fp_line
			(start -0.12065 -0.2794)
			(end -0.12065 -0.3048)
			(stroke
				(width 0.1)
				(type default)
			)
			(layer "B.Fab")
		)
		(fp_line
			(start -0.120396 0.2794)
			(end 0.12065 0.2794)
			(stroke
				(width 0.1)
				(type default)
			)
			(layer "B.Fab")
		)
		(fp_line
			(start -0.120396 0.3048)
			(end -0.120396 0.2794)
			(stroke
				(width 0.1)
				(type default)
			)
			(layer "B.Fab")
		)
		(fp_line
			(start 0.12065 -0.305054)
			(end 0.12065 -0.2794)
			(stroke
				(width 0.1)
				(type default)
			)
			(layer "B.Fab")
		)
		(fp_line
			(start 0.12065 -0.2794)
			(end -0.12065 -0.2794)
			(stroke
				(width 0.1)
				(type default)
			)
			(layer "B.Fab")
		)
		(fp_line
			(start 0.12065 0.2794)
			(end 0.12065 0.3048)
			(stroke
				(width 0.1)
				(type default)
			)
			(layer "B.Fab")
		)
		(fp_line
			(start 0.12065 0.3048)
			(end 0.67945 0.3048)
			(stroke
				(width 0.1)
				(type default)
			)
			(layer "B.Fab")
		)
		(fp_line
			(start 0.67945 -0.305054)
			(end 0.12065 -0.305054)
			(stroke
				(width 0.1)
				(type default)
			)
			(layer "B.Fab")
		)
		(fp_line
			(start 0.67945 0.3048)
			(end 0.67945 -0.305054)
			(stroke
				(width 0.1)
				(type default)
			)
			(layer "B.Fab")
		)
		(pad "1" smd circle
			(at 0.40005 0 180)
			(size 0 0)
			(layers "B.Cu" "B.Mask" "B.Paste")
			(net "M_H_CPU0_ALERT_N")
		)
		(pad "2" smd circle
			(at -0.40005 0 180)
			(size 0 0)
			(layers "B.Cu" "B.Mask" "B.Paste")
			(net "M_H_CPU0_ALERT_R_N")
		)
	)
)
